# S9S_MB_2U (Grand Teton) — schematic netlist excerpt (pin names and nets, part order shuffled) for the footprints in the layout excerpt that follows; sources: Cadence DE-HDL packaged netlist, KiCad conversion of 03242023_DA0F0TMBIJ0_F0T_Motherboard_J_brd_V01_OCP.brd

J17  SCONN288_ADR50017P130CC  SCONN288_ADR50017-P130CC IO  pkg DDR288S_1-1VXB  page 98
  VIN_BULK0  = P12V_S3_AUX_CPU1_NVDIMM
  RFU0  = TP_CHA_CPU1_DIMM1_FRU_0
  VIN_MGMT  = P3V3_AUX
  HSCL  = I3C_SPD_DDRABCD_CPU1_LVC1_SCL_R
  HSDA  = I3C_SPD_DDRABCD_CPU1_LVC1_SDA
  VSS0  = GND
  DQ0_A  = M_A_CPU1_SA_DQ<0>
  VSS1  = GND
  DQ1_A  = M_A_CPU1_SA_DQ<1>
  VSS2  = GND
  DQS0_A_T  = M_A_CPU1_SA_DQS_DP<0>
  DQS0_A_C  = M_A_CPU1_SA_DQS_DN<0>
  VSS3  = GND
  DQ4_A  = M_A_CPU1_SA_DQ<4>
  VSS4  = GND
  DQ5_A  = M_A_CPU1_SA_DQ<5>
  VSS5  = GND
  DQ8_A  = M_A_CPU1_SA_DQ<8>
  VSS6  = GND
  DQ9_A  = M_A_CPU1_SA_DQ<9>
  VSS7  = GND
  DQS1_A_T  = M_A_CPU1_SA_DQS_DP<1>
  DQS1_A_C  = M_A_CPU1_SA_DQS_DN<1>
  VSS8  = GND
  DQ12_A  = M_A_CPU1_SA_DQ<12>
  VSS9  = GND
  DQ13_A  = M_A_CPU1_SA_DQ<13>
  VSS10  = GND
  DQ16_A  = M_A_CPU1_SA_DQ<16>
  VSS11  = GND
  DQ17_A  = M_A_CPU1_SA_DQ<17>
  VSS12  = GND
  DQS2_A_T  = M_A_CPU1_SA_DQS_DP<2>
  DQS2_A_C  = M_A_CPU1_SA_DQS_DN<2>
  VSS13  = GND
  DQ20_A  = M_A_CPU1_SA_DQ<20>
  VSS14  = GND
  DQ21_A  = M_A_CPU1_SA_DQ<21>
  VSS15  = GND
  DQ24_A  = M_A_CPU1_SA_DQ<24>
  VSS16  = GND
  DQ25_A  = M_A_CPU1_SA_DQ<25>
  VSS17  = GND
  DQS3_A_T  = M_A_CPU1_SA_DQS_DP<3>
  DQS3_A_C  = M_A_CPU1_SA_DQS_DN<3>
  VSS18  = GND
  DQ28_A  = M_A_CPU1_SA_DQ<28>
  VSS19  = GND
  DQ29_A  = M_A_CPU1_SA_DQ<29>
  VSS20  = GND
  CB0_A  = M_A_CPU1_SA_CB<0>
  VSS21  = GND
  CB1_A  = M_A_CPU1_SA_CB<1>
  VSS22  = GND
  DQS4_A_T  = M_A_CPU1_SA_DQS_DP<4>
  DQS4_A_C  = M_A_CPU1_SA_DQS_DN<4>
  VSS23  = GND
  CB4_A  = M_A_CPU1_SA_CB<4>
  VSS24  = GND
  CB5_A  = M_A_CPU1_SA_CB<5>
  VSS25  = GND
  ALERT_N  = M_A_CPU1_ALERT_N
  VSS26  = GND
  CS0_A_N  = M_A_CPU1_SA_CS_N<0>
  VSS27  = GND
  CA0_A  = M_A_CPU1_SA_CA<0>
  VSS28  = GND
  CA2_A  = M_A_CPU1_SA_CA<2>
  VSS29  = GND
  CA4_A  = M_A_CPU1_SA_CA<4>
  VSS30  = GND
  CA6_A  = M_A_CPU1_SA_CA<6>
  VSS31  = GND
  PAR_A  = M_A_CPU1_SA_PAR
  VSS32  = GND
  CA0_B  = M_A_CPU1_SB_CA<0>
  VSS33  = GND
  CA2_B  = M_A_CPU1_SB_CA<2>
  VSS34  = GND
  CA4_B  = M_A_CPU1_SB_CA<4>
  VSS35  = GND
  CA6_B  = M_A_CPU1_SB_CA<6>
  VSS36  = GND
  CS0_B_N  = M_A_CPU1_SB_CS_N<0>
  VSS37  = GND
  \lbd||rsp_a_n\  = M_A_CPU1_SA_RSP<0>
  \lbs||rsp_b_n\  = M_A_CPU1_SB_RSP<0>
  VSS38  = GND
  CB4_B  = M_A_CPU1_SB_CB<4>
  VSS39  = GND
  CB5_B  = M_A_CPU1_SB_CB<5>
  VSS40  = GND
  \dqs9_b_t||tdqs9_b_t||dbi4_b_n\  = M_A_CPU1_SB_DQS_DP<9>
  \dqs9_b_c||tdqs9_b_c\  = M_A_CPU1_SB_DQS_DN<9>
  VSS41  = GND
  CB0_B  = M_A_CPU1_SB_CB<0>
  VSS42  = GND
  CB1_B  = M_A_CPU1_SB_CB<1>
  VSS43  = GND
  DQ0_B  = M_A_CPU1_SB_DQ<0>
  VSS44  = GND
  DQ1_B  = M_A_CPU1_SB_DQ<1>
  VSS45  = GND
  DQS0_B_T  = M_A_CPU1_SB_DQS_DP<0>
  DQS0_B_C  = M_A_CPU1_SB_DQS_DN<0>
  VSS46  = GND
  DQ4_B  = M_A_CPU1_SB_DQ<4>
  VSS47  = GND
  DQ5_B  = M_A_CPU1_SB_DQ<5>
  VSS48  = GND
  DQ8_B  = M_A_CPU1_SB_DQ<8>
  VSS49  = GND
  DQ9_B  = M_A_CPU1_SB_DQ<9>
  VSS50  = GND
  DQS1_B_T  = M_A_CPU1_SB_DQS_DP<1>
  DQS1_B_C  = M_A_CPU1_SB_DQS_DN<1>
  VSS51  = GND
  DQ12_B  = M_A_CPU1_SB_DQ<12>
  VSS52  = GND
  DQ13_B  = M_A_CPU1_SB_DQ<13>
  VSS53  = GND
  DQ16_B  = M_A_CPU1_SB_DQ<16>
  VSS54  = GND
  DQ17_B  = M_A_CPU1_SB_DQ<17>
  VSS55  = GND
  DQS2_B_T  = M_A_CPU1_SB_DQS_DP<2>
  DQS2_B_C  = M_A_CPU1_SB_DQS_DN<2>
  VSS56  = GND
  DQ20_B  = M_A_CPU1_SB_DQ<20>
  VSS57  = GND
  DQ21_B  = M_A_CPU1_SB_DQ<21>
  VSS58  = GND
  DQ24_B  = M_A_CPU1_SB_DQ<24>
  VSS59  = GND
  DQ25_B  = M_A_CPU1_SB_DQ<25>
  VSS60  = GND
  DQS3_B_T  = M_A_CPU1_SB_DQS_DP<3>
  DQS3_B_C  = M_A_CPU1_SB_DQS_DN<3>
  VSS61  = GND
  DQ28_B  = M_A_CPU1_SB_DQ<28>
  VSS62  = GND
  DQ29_B  = M_A_CPU1_SB_DQ<29>
  VSS63  = GND
  RFU1  = TP_CHA_CPU1_DIMM1_FRU_1
  VIN_BULK1  = P12V_S3_AUX_CPU1_NVDIMM
  VIN_BULK2  = P12V_S3_AUX_CPU1_NVDIMM
  \pwr_good||fail_n\  = PWRGD_CHA_CPU1_DIMM1
  HSA  = PD_CHA_CPU1_DIMM1_SAA
  RFU2  = TP_CHA_CPU1_DIMM1_FRU_2
  RFU3  = TP_CHA_CPU1_DIMM1_FRU_3
  VSS64  = GND
  DQ2_A  = M_A_CPU1_SA_DQ<2>
  VSS65  = GND
  DQ3_A  = M_A_CPU1_SA_DQ<3>
  VSS66  = GND
  \dqs5_a_c||tdqs5_a_c||dqs5_a_t||tdqs5_a_t\  = M_A_CPU1_SA_DQS_DN<5>
  \dqs5_a_t||tdqs5_a_t\  = M_A_CPU1_SA_DQS_DP<5>
  VSS67  = GND
  DQ6_A  = M_A_CPU1_SA_DQ<6>
  VSS68  = GND
  DQ7_A  = M_A_CPU1_SA_DQ<7>
  VSS69  = GND
  DQ10_A  = M_A_CPU1_SA_DQ<10>
  VSS70  = GND
  DQ11_A  = M_A_CPU1_SA_DQ<11>
  VSS71  = GND
  \dqs6_a_c||tdqs6_a_c||dqs6_a_t||tdqs6_a_t\  = M_A_CPU1_SA_DQS_DN<6>
  \dqs6_a_t||tdqs6_a_t\  = M_A_CPU1_SA_DQS_DP<6>
  VSS72  = GND
  DQ14_A  = M_A_CPU1_SA_DQ<14>
  VSS73  = GND
  DQ15_A  = M_A_CPU1_SA_DQ<15>
  VSS74  = GND
  DQ18_A  = M_A_CPU1_SA_DQ<18>
  VSS75  = GND
  DQ19_A  = M_A_CPU1_SA_DQ<19>
  VSS76  = GND
  \dqs7_a_c||tdqs7_a_c\  = M_A_CPU1_SA_DQS_DN<7>
  \dqs7_a_t||tdqs7_a_t\  = M_A_CPU1_SA_DQS_DP<7>
  VSS77  = GND
  DQ22_A  = M_A_CPU1_SA_DQ<22>
  VSS78  = GND
  DQ23_A  = M_A_CPU1_SA_DQ<23>
  VSS79  = GND
  DQ26_A  = M_A_CPU1_SA_DQ<26>
  VSS80  = GND
  DQ27_A  = M_A_CPU1_SA_DQ<27>
  VSS81  = GND
  \dqs8_a_c||tdqs8_a_c\  = M_A_CPU1_SA_DQS_DN<8>
  \dqs8_a_t||tdqs8_a_t\  = M_A_CPU1_SA_DQS_DP<8>
  VSS82  = GND
  DQ30_A  = M_A_CPU1_SA_DQ<30>
  VSS83  = GND
  DQ31_A  = M_A_CPU1_SA_DQ<31>
  VSS84  = GND
  CB2_A  = M_A_CPU1_SA_CB<2>
  VSS85  = GND
  CB3_A  = M_A_CPU1_SA_CB<3>
  VSS86  = GND
  \dqs9_a_c||tdqs9_a_c\  = M_A_CPU1_SA_DQS_DN<9>
  \dqs9_a_t||tdqs9_a_t\  = M_A_CPU1_SA_DQS_DP<9>
  VSS87  = GND
  CB6_A  = M_A_CPU1_SA_CB<6>
  VSS88  = GND
  CB7_A  = M_A_CPU1_SA_CB<7>
  VSS89  = GND
  RESET_N  = RST_M_AB_CPU1_FPGA_N
  VSS90  = GND
  CS1_A_N  = M_A_CPU1_SA_CS_N<1>
  VSS91  = GND
  CA1_A  = M_A_CPU1_SA_CA<1>
  VSS92  = GND
  CA3_A  = M_A_CPU1_SA_CA<3>
  VSS93  = GND
  CA5_A  = M_A_CPU1_SA_CA<5>
  VSS94  = GND
  CK_T  = M_A_CPU1_CLK_DP<0>
  CK_C  = M_A_CPU1_CLK_DN<0>
  VSS95  = GND
  RFU4  = TP_CHA_CPU1_DIMM1_FRU_4
  CA1_B  = M_A_CPU1_SB_CA<1>
  VSS96  = GND
  CA3_B  = M_A_CPU1_SB_CA<3>
  VSS97  = GND
  CA5_B  = M_A_CPU1_SB_CA<5>
  VSS98  = GND
  PAR_B  = M_A_CPU1_SB_PAR
  VSS99  = GND
  CS1_B_N  = M_A_CPU1_SB_CS_N<1>
  VSS100  = GND
  RFU5  = TP_CHA_CPU1_DIMM1_FRU_5
  RFU6  = TP_CHA_CPU1_DIMM1_FRU_6
  VSS101  = GND
  CB6_B  = M_A_CPU1_SB_CB<6>
  VSS102  = GND
  CB7_B  = M_A_CPU1_SB_CB<7>
  VSS103  = GND
  DQS4_B_C  = M_A_CPU1_SB_DQS_DN<4>
  DQS4_B_T  = M_A_CPU1_SB_DQS_DP<4>
  VSS104  = GND
  CB2_B  = M_A_CPU1_SB_CB<2>
  VSS105  = GND
  CB3_B  = M_A_CPU1_SB_CB<3>
  VSS106  = GND
  DQ2_B  = M_A_CPU1_SB_DQ<2>
  VSS107  = GND
  DQ3_B  = M_A_CPU1_SB_DQ<3>
  VSS108  = GND
  \dqs5_b_c||tdqs5_b_c\  = M_A_CPU1_SB_DQS_DN<5>
  \dqs5_b_t||tdqs5_b_t\  = M_A_CPU1_SB_DQS_DP<5>
  VSS109  = GND
  DQ6_B  = M_A_CPU1_SB_DQ<6>
  VSS110  = GND
  DQ7_B  = M_A_CPU1_SB_DQ<7>
  VSS111  = GND
  DQ10_B  = M_A_CPU1_SB_DQ<10>
  VSS112  = GND
  DQ11_B  = M_A_CPU1_SB_DQ<11>
  VSS113  = GND
  \dqs6_b_c||tdqs6_b_c\  = M_A_CPU1_SB_DQS_DN<6>
  \dqs6_b_t||tdqs6_b_t\  = M_A_CPU1_SB_DQS_DP<6>
  VSS114  = GND
  DQ14_B  = M_A_CPU1_SB_DQ<14>
  VSS115  = GND
  DQ15_B  = M_A_CPU1_SB_DQ<15>
  VSS116  = GND
  DQ18_B  = M_A_CPU1_SB_DQ<18>
  VSS117  = GND
  DQ19_B  = M_A_CPU1_SB_DQ<19>
  VSS118  = GND
  \dqs7_b_c||tdqs7_b_c\  = M_A_CPU1_SB_DQS_DN<7>
  \dqs7_b_t||tdqs7_b_t\  = M_A_CPU1_SB_DQS_DP<7>
  VSS119  = GND
  DQ22_B  = M_A_CPU1_SB_DQ<22>
  VSS120  = GND
  DQ23_B  = M_A_CPU1_SB_DQ<23>
  VSS121  = GND
  DQ26_B  = M_A_CPU1_SB_DQ<26>
  VSS122  = GND
  DQ27_B  = M_A_CPU1_SB_DQ<27>
  VSS123  = GND
  \dqs8_b_c||tdqs8_b_c\  = M_A_CPU1_SB_DQS_DN<8>
  \dqs8_b_t||tdqs8_b_t\  = M_A_CPU1_SB_DQS_DP<8>
  VSS124  = GND
  DQ30_B  = M_A_CPU1_SB_DQ<30>
  VSS125  = GND
  DQ31_B  = M_A_CPU1_SB_DQ<31>
  VSS126  = GND
  G1  = GND
  G2  = GND
  G3  = GND

(kicad_pcb
	(version 20260206)
	(generator "pcbnew")
	(generator_version "10.0")
	(general
		(thickness 1.6)
		(legacy_teardrops no)
	)
	(paper "A4")
	(title_block
		(title "03242023_DA0F0TMBIJ0_F0T_Motherboard_J_brd_V01_OCP.brd")
		(comment 1 "Grand Teton / footprint 1335 of 6105 (J17), pads 229-274 of 291")
	)
	(layers
		(0 "F.Cu" signal "TOP")
		(4 "In1.Cu" signal "GND")
		(6 "In2.Cu" signal "IN1")
		(8 "In3.Cu" signal "GND1")
		(10 "In4.Cu" signal "IN2")
		(12 "In5.Cu" signal "GND2")
		(14 "In6.Cu" signal "IN3")
		(16 "In7.Cu" signal "GND3")
		(18 "In8.Cu" signal "VCC")
		(20 "In9.Cu" signal "VCC1")
		(22 "In10.Cu" signal "GND4")
		(24 "In11.Cu" signal "IN4")
		(26 "In12.Cu" signal "GND5")
		(28 "In13.Cu" signal "IN5")
		(30 "In14.Cu" signal "GND6")
		(32 "In15.Cu" signal "IN6")
		(34 "In16.Cu" signal "GND7")
		(2 "B.Cu" signal "BOTTOM")
		(9 "F.Adhes" user "F.Adhesive")
		(11 "B.Adhes" user "B.Adhesive")
		(13 "F.Paste" user "Package Geometry/Pastemask Top")
		(15 "B.Paste" user "Package Geometry/Pastemask Bottom")
		(5 "F.SilkS" user "Ref Des/Silkscreen Top")
		(7 "B.SilkS" user "Ref Des/Silkscreen Bottom")
		(1 "F.Mask" user "Board Geometry/Soldermask Top")
		(3 "B.Mask" user "Board Geometry/Soldermask Bottom")
		(17 "Dwgs.User" user "User.Drawings")
		(19 "Cmts.User" user "User.Comments")
		(21 "Eco1.User" user "User.Eco1")
		(23 "Eco2.User" user "User.Eco2")
		(25 "Edge.Cuts" user "Board Geometry/Outline")
		(27 "Margin" user)
		(31 "F.CrtYd" user "Package Geometry/Place Bound Top")
		(29 "B.CrtYd" user "Package Geometry/Place Bound Bottom")
		(35 "F.Fab" user "Ref Des/Assembly Top")
		(33 "B.Fab" user "Ref Des/Assembly Bottom")
	)
	(footprint ""
		(layer "F.Cu")
		(at 55.45328 -258.091686)
		(property "Reference" "J17"
			(at -0.178562 -81.717134 0)
			(unlocked yes)
			(layer "F.SilkS")
			(effects
				(font
					(size 0.7874 0.5842)
					(thickness 0.1524)
				)
				(justify left)
			)
		)
		(property "Value" ""
			(at 0 0 0)
			(layer "F.Fab")
			(effects
				(font
					(size 1.27 1.27)
				)
			)
		)
		(duplicate_pad_numbers_are_jumpers no)
		(pad "229" smd rect
			(at 2.050034 13.17498 270)
			(size 0.519938 1.4986)
			(layers "F.Cu" "F.Mask" "F.Paste")
			(net "M_A_CPU1_SB_CS_N<1>")
		)
		(pad "230" smd rect
			(at 2.050034 14.025118 270)
			(size 0.519938 1.4986)
			(layers "F.Cu" "F.Mask" "F.Paste")
			(net "GND")
		)
		(pad "231" smd rect
			(at 2.050034 14.875002 270)
			(size 0.519938 1.4986)
			(layers "F.Cu" "F.Mask" "F.Paste")
			(net "TP_CHA_CPU1_DIMM1_FRU_5")
		)
		(pad "232" smd rect
			(at 2.050034 15.724886 270)
			(size 0.519938 1.4986)
			(layers "F.Cu" "F.Mask" "F.Paste")
			(net "TP_CHA_CPU1_DIMM1_FRU_6")
		)
		(pad "233" smd rect
			(at 2.050034 16.575024 270)
			(size 0.519938 1.4986)
			(layers "F.Cu" "F.Mask" "F.Paste")
			(net "GND")
		)
		(pad "234" smd rect
			(at 2.050034 17.424908 270)
			(size 0.519938 1.4986)
			(layers "F.Cu" "F.Mask" "F.Paste")
			(net "M_A_CPU1_SB_CB<6>")
		)
		(pad "235" smd rect
			(at 2.050034 18.275046 270)
			(size 0.519938 1.4986)
			(layers "F.Cu" "F.Mask" "F.Paste")
			(net "GND")
		)
		(pad "236" smd rect
			(at 2.050034 19.12493 270)
			(size 0.519938 1.4986)
			(layers "F.Cu" "F.Mask" "F.Paste")
			(net "M_A_CPU1_SB_CB<7>")
		)
		(pad "237" smd rect
			(at 2.050034 19.975068 270)
			(size 0.519938 1.4986)
			(layers "F.Cu" "F.Mask" "F.Paste")
			(net "GND")
		)
		(pad "238" smd rect
			(at 2.050034 20.824952 270)
			(size 0.519938 1.4986)
			(layers "F.Cu" "F.Mask" "F.Paste")
			(net "M_A_CPU1_SB_DQS_DN<4>")
		)
		(pad "239" smd rect
			(at 2.050034 21.67509 270)
			(size 0.519938 1.4986)
			(layers "F.Cu" "F.Mask" "F.Paste")
			(net "M_A_CPU1_SB_DQS_DP<4>")
		)
		(pad "240" smd rect
			(at 2.050034 22.524974 270)
			(size 0.519938 1.4986)
			(layers "F.Cu" "F.Mask" "F.Paste")
			(net "GND")
		)
		(pad "241" smd rect
			(at 2.050034 23.375112 270)
			(size 0.519938 1.4986)
			(layers "F.Cu" "F.Mask" "F.Paste")
			(net "M_A_CPU1_SB_CB<2>")
		)
		(pad "242" smd rect
			(at 2.050034 24.224996 270)
			(size 0.519938 1.4986)
			(layers "F.Cu" "F.Mask" "F.Paste")
			(net "GND")
		)
		(pad "243" smd rect
			(at 2.050034 25.07488 270)
			(size 0.519938 1.4986)
			(layers "F.Cu" "F.Mask" "F.Paste")
			(net "M_A_CPU1_SB_CB<3>")
		)
		(pad "244" smd rect
			(at 2.050034 25.925018 270)
			(size 0.519938 1.4986)
			(layers "F.Cu" "F.Mask" "F.Paste")
			(net "GND")
		)
		(pad "245" smd rect
			(at 2.050034 26.774902 270)
			(size 0.519938 1.4986)
			(layers "F.Cu" "F.Mask" "F.Paste")
			(net "M_A_CPU1_SB_DQ<2>")
		)
		(pad "246" smd rect
			(at 2.050034 27.62504 270)
			(size 0.519938 1.4986)
			(layers "F.Cu" "F.Mask" "F.Paste")
			(net "GND")
		)
		(pad "247" smd rect
			(at 2.050034 28.474924 270)
			(size 0.519938 1.4986)
			(layers "F.Cu" "F.Mask" "F.Paste")
			(net "M_A_CPU1_SB_DQ<3>")
		)
		(pad "248" smd rect
			(at 2.050034 29.325062 270)
			(size 0.519938 1.4986)
			(layers "F.Cu" "F.Mask" "F.Paste")
			(net "GND")
		)
		(pad "249" smd rect
			(at 2.050034 30.174946 270)
			(size 0.519938 1.4986)
			(layers "F.Cu" "F.Mask" "F.Paste")
			(net "M_A_CPU1_SB_DQS_DN<5>")
		)
		(pad "250" smd rect
			(at 2.050034 31.025084 270)
			(size 0.519938 1.4986)
			(layers "F.Cu" "F.Mask" "F.Paste")
			(net "M_A_CPU1_SB_DQS_DP<5>")
		)
		(pad "251" smd rect
			(at 2.050034 31.874968 270)
			(size 0.519938 1.4986)
			(layers "F.Cu" "F.Mask" "F.Paste")
			(net "GND")
		)
		(pad "252" smd rect
			(at 2.050034 32.725106 270)
			(size 0.519938 1.4986)
			(layers "F.Cu" "F.Mask" "F.Paste")
			(net "M_A_CPU1_SB_DQ<6>")
		)
		(pad "253" smd rect
			(at 2.050034 33.57499 270)
			(size 0.519938 1.4986)
			(layers "F.Cu" "F.Mask" "F.Paste")
			(net "GND")
		)
		(pad "254" smd rect
			(at 2.050034 34.425128 270)
			(size 0.519938 1.4986)
			(layers "F.Cu" "F.Mask" "F.Paste")
			(net "M_A_CPU1_SB_DQ<7>")
		)
		(pad "255" smd rect
			(at 2.050034 35.275012 270)
			(size 0.519938 1.4986)
			(layers "F.Cu" "F.Mask" "F.Paste")
			(net "GND")
		)
		(pad "256" smd rect
			(at 2.050034 36.124896 270)
			(size 0.519938 1.4986)
			(layers "F.Cu" "F.Mask" "F.Paste")
			(net "M_A_CPU1_SB_DQ<10>")
		)
		(pad "257" smd rect
			(at 2.050034 36.975034 270)
			(size 0.519938 1.4986)
			(layers "F.Cu" "F.Mask" "F.Paste")
			(net "GND")
		)
		(pad "258" smd rect
			(at 2.050034 37.824918 270)
			(size 0.519938 1.4986)
			(layers "F.Cu" "F.Mask" "F.Paste")
			(net "M_A_CPU1_SB_DQ<11>")
		)
		(pad "259" smd rect
			(at 2.050034 38.675056 270)
			(size 0.519938 1.4986)
			(layers "F.Cu" "F.Mask" "F.Paste")
			(net "GND")
		)
		(pad "260" smd rect
			(at 2.050034 39.52494 270)
			(size 0.519938 1.4986)
			(layers "F.Cu" "F.Mask" "F.Paste")
			(net "M_A_CPU1_SB_DQS_DN<6>")
		)
		(pad "261" smd rect
			(at 2.050034 40.375078 270)
			(size 0.519938 1.4986)
			(layers "F.Cu" "F.Mask" "F.Paste")
			(net "M_A_CPU1_SB_DQS_DP<6>")
		)
		(pad "262" smd rect
			(at 2.050034 41.224962 270)
			(size 0.519938 1.4986)
			(layers "F.Cu" "F.Mask" "F.Paste")
			(net "GND")
		)
		(pad "263" smd rect
			(at 2.050034 42.0751 270)
			(size 0.519938 1.4986)
			(layers "F.Cu" "F.Mask" "F.Paste")
			(net "M_A_CPU1_SB_DQ<14>")
		)
		(pad "264" smd rect
			(at 2.050034 42.924984 270)
			(size 0.519938 1.4986)
			(layers "F.Cu" "F.Mask" "F.Paste")
			(net "GND")
		)
		(pad "265" smd rect
			(at 2.050034 43.775122 270)
			(size 0.519938 1.4986)
			(layers "F.Cu" "F.Mask" "F.Paste")
			(net "M_A_CPU1_SB_DQ<15>")
		)
		(pad "266" smd rect
			(at 2.050034 44.625006 270)
			(size 0.519938 1.4986)
			(layers "F.Cu" "F.Mask" "F.Paste")
			(net "GND")
		)
		(pad "267" smd rect
			(at 2.050034 45.47489 270)
			(size 0.519938 1.4986)
			(layers "F.Cu" "F.Mask" "F.Paste")
			(net "M_A_CPU1_SB_DQ<18>")
		)
		(pad "268" smd rect
			(at 2.050034 46.325028 270)
			(size 0.519938 1.4986)
			(layers "F.Cu" "F.Mask" "F.Paste")
			(net "GND")
		)
		(pad "269" smd rect
			(at 2.050034 47.174912 270)
			(size 0.519938 1.4986)
			(layers "F.Cu" "F.Mask" "F.Paste")
			(net "M_A_CPU1_SB_DQ<19>")
		)
		(pad "270" smd rect
			(at 2.050034 48.02505 270)
			(size 0.519938 1.4986)
			(layers "F.Cu" "F.Mask" "F.Paste")
			(net "GND")
		)
		(pad "271" smd rect
			(at 2.050034 48.874934 270)
			(size 0.519938 1.4986)
			(layers "F.Cu" "F.Mask" "F.Paste")
			(net "M_A_CPU1_SB_DQS_DN<7>")
		)
		(pad "272" smd rect
			(at 2.050034 49.725072 270)
			(size 0.519938 1.4986)
			(layers "F.Cu" "F.Mask" "F.Paste")
			(net "M_A_CPU1_SB_DQS_DP<7>")
		)
		(pad "273" smd rect
			(at 2.050034 50.574956 270)
			(size 0.519938 1.4986)
			(layers "F.Cu" "F.Mask" "F.Paste")
			(net "GND")
		)
		(pad "274" smd rect
			(at 2.050034 51.425094 270)
			(size 0.519938 1.4986)
			(layers "F.Cu" "F.Mask" "F.Paste")
			(net "M_A_CPU1_SB_DQ<22>")
		)
	)
)
